#ISCELL
  mstr_misc dns *
  *
#ISCELL
  mstr_symbols design_note *
  *
#ISCELL
  mstr_symbols intel_corp_bpage *
  *
#ISCELL
  mstr_standard offpage *
  page205_i1
#ISCELL
  mstr_symbols pvsa_cpu0 *
  page205_i11
#CELL
  mstr_discrete capp *
  page205_i12
#ISCELL
  mstr_symbols gnd *
  page205_i13
#CELL
  mstr_discrete capp *
  page205_i14
#ISCELL
  mstr_symbols gnd *
  page205_i15
#CELL
  mstr_discrete cap *
  page205_i16
#ISCELL
  mstr_standard offpage *
  page205_i2
#CELL
  mstr_discrete cap *
  page205_i20
#ISCELL
  mstr_standard offpage *
  page205_i22
#ISCELL
  mstr_symbols pvsa_cpu0 *
  page205_i23
#CELL
  mstr_discrete res *
  page205_i24
#CELL
  mstr_discrete cap *
  page205_i25
#CELL
  mstr_discrete res *
  page205_i26
#ISCELL
  mstr_standard offpage *
  page205_i27
#ISCELL
  mstr_symbols gnd *
  page205_i28
#CELL
  mstr_discrete res *
  page205_i29
#ISCELL
  mstr_standard offpage *
  page205_i3
#CELL
  mstr_discrete res *
  page205_i30
#CELL
  dev_discrete cap_a *
  page205_i31
#CELL
  mstr_discrete cap *
  page205_i32
#CELL
  mstr_discrete cap *
  page205_i33
#CELL
  mstr_discrete cap *
  page205_i34
#CELL
  mstr_discrete cap *
  page205_i35
#ISCELL
  mstr_symbols vcc_core *
  page205_i36
#CELL
  mstr_discrete res *
  page205_i37
#ISCELL
  mstr_standard offpage *
  page205_i38
#ISCELL
  mstr_symbols gnd *
  page205_i39
#ISCELL
  mstr_symbols pvsa_cpu0 *
  page205_i4
#ISCELL
  mstr_standard offpage *
  page205_i40
#ISCELL
  mstr_standard offpage *
  page205_i41
#ISCELL
  mstr_symbols p5v_stby *
  page205_i42
#CELL
  dev_discrete cap_a *
  page205_i43
#CELL
  mstr_discrete res *
  page205_i45
#CELL
  mstr_discrete ir354xx *
  page205_i46
#CELL
  dev_discrete cap_a *
  page205_i5
#ISCELL
  mstr_symbols gnd *
  page205_i6
#CELL
  mstr_discrete res *
  page205_i62
#ISCELL
  mstr_symbols gnd *
  page205_i63
#CELL
  mstr_discrete cap *
  page205_i65
#ISCELL
  mstr_symbols gnd *
  page205_i66
#ISCELL
  mstr_symbols gnd *
  page205_i67
#CELL
  dev_discrete cap_a *
  page205_i69
#ISCELL
  mstr_symbols gnd *
  page205_i70
#CELL
  mstr_discrete cap *
  page205_i76
#CELL
  mstr_discrete res *
  page205_i78
#CELL
  mstr_discrete res *
  page205_i81
#CELL
  w_hdl ind-300nh-20-gp *
  page205_i82
#CELL
  w_hdl sc1u10v2kx-4-gp *
  page205_i83
#CELL
  w_hdl 1r3f-gp *
  page205_i84
